(kicad_pcb
	(version 20241229)
	(generator "pcbnew")
	(generator_version "9.0")
	(general
		(thickness 1.6296)
		(legacy_teardrops no)
	)
	(paper "A3")
	(title_block
		(title "Thunderbolt to 10GbE adapter")
		(date "2026-04-21")
		(rev "1.1.0")
		(company "Antmicro Ltd")
		(comment 1 "www.antmicro.com")
		(comment 9 "footprints 300-303 of 703")
	)
	(layers
		(0 "F.Cu" signal)
		(4 "In1.Cu" signal)
		(6 "In2.Cu" signal)
		(8 "In3.Cu" signal)
		(10 "In4.Cu" signal)
		(12 "In5.Cu" signal)
		(14 "In6.Cu" signal)
		(2 "B.Cu" signal)
		(9 "F.Adhes" user "F.Adhesive")
		(11 "B.Adhes" user "B.Adhesive")
		(13 "F.Paste" user)
		(15 "B.Paste" user)
		(5 "F.SilkS" user "F.Silkscreen")
		(7 "B.SilkS" user "B.Silkscreen")
		(1 "F.Mask" user)
		(3 "B.Mask" user)
		(17 "Dwgs.User" user "User.Drawings")
		(19 "Cmts.User" user "User.Comments")
		(21 "Eco1.User" user "User.Eco1")
		(23 "Eco2.User" user "User.Eco2")
		(25 "Edge.Cuts" user)
		(27 "Margin" user)
		(31 "F.CrtYd" user "F.Courtyard")
		(29 "B.CrtYd" user "B.Courtyard")
		(35 "F.Fab" user)
		(33 "B.Fab" user)
	)
	(footprint "antmicro-footprints:C_0402_1005Metric"
		(layer "F.Cu")
		(at 165.5 67.8 180)
		(descr "Capacitor SMD 0402")
		(tags "capacitor SMD 0402")
		(property "Reference" "C277"
			(at 0.9 0.6 180)
			(layer "F.SilkS")
			(effects
				(font
					(size 0.7 0.7)
					(thickness 0.15)
				)
				(justify left bottom)
			)
		)
		(property "Value" "C_100n_0402"
			(at -1.022927 2.155213 180)
			(layer "F.Fab")
			(effects
				(font
					(size 0.7 0.7)
					(thickness 0.15)
				)
				(justify left bottom)
			)
		)
		(property "Datasheet" "https://www.murata.com/products/productdetail?partno=GRM155R61H104KE14%23"
			(at 0 0 180)
			(layer "F.Fab")
			(hide yes)
			(effects
				(font
					(size 1.27 1.27)
					(thickness 0.15)
				)
			)
		)
		(property "Description" "SMD Multilayer Ceramic Capacitor, 0.1 µF, 50 V, 0402 [1005 Metric], ± 10%, X5R, GRM Series"
			(at 0 0 180)
			(layer "F.Fab")
			(hide yes)
			(effects
				(font
					(size 1.27 1.27)
					(thickness 0.15)
				)
			)
		)
		(property "MPN" "GRM155R61H104KE14D"
			(at 0 0 180)
			(unlocked yes)
			(layer "F.Fab")
			(hide yes)
			(effects
				(font
					(size 1 1)
					(thickness 0.15)
				)
			)
		)
		(property "Val" "100n"
			(at 0 0 180)
			(unlocked yes)
			(layer "F.Fab")
			(hide yes)
			(effects
				(font
					(size 1 1)
					(thickness 0.15)
				)
			)
		)
		(property "Voltage" "50V"
			(at 0 0 180)
			(unlocked yes)
			(layer "F.Fab")
			(hide yes)
			(effects
				(font
					(size 1 1)
					(thickness 0.15)
				)
			)
		)
		(property "Dielectric" "X5R"
			(at 0 0 180)
			(unlocked yes)
			(layer "F.Fab")
			(hide yes)
			(effects
				(font
					(size 1 1)
					(thickness 0.15)
				)
			)
		)
		(property "Manufacturer" "Murata"
			(at 0 0 180)
			(unlocked yes)
			(layer "F.Fab")
			(hide yes)
			(effects
				(font
					(size 1 1)
					(thickness 0.15)
				)
			)
		)
		(property "License" "Apache-2.0"
			(at 0 0 180)
			(unlocked yes)
			(layer "F.Fab")
			(hide yes)
			(effects
				(font
					(size 1 1)
					(thickness 0.15)
				)
			)
		)
		(property "Author" "Antmicro"
			(at 0 0 180)
			(unlocked yes)
			(layer "F.Fab")
			(hide yes)
			(effects
				(font
					(size 1 1)
					(thickness 0.15)
				)
			)
		)
		(sheetname "/X710-AT2 Misc/")
		(sheetfile "x710-at2-mics.kicad_sch")
		(attr smd)
		(fp_rect
			(start -0.925 -0.47)
			(end 0.925 0.47)
			(stroke
				(width 0.05)
				(type default)
			)
			(fill no)
			(layer "F.CrtYd")
		)
		(fp_line
			(start 0.504 0.248)
			(end -0.494 0.248)
			(stroke
				(width 0.15)
				(type solid)
			)
			(layer "F.Fab")
		)
		(fp_line
			(start 0.504 -0.25)
			(end 0.504 0.248)
			(stroke
				(width 0.15)
				(type solid)
			)
			(layer "F.Fab")
		)
		(fp_line
			(start -0.494 0.248)
			(end -0.494 -0.25)
			(stroke
				(width 0.15)
				(type solid)
			)
			(layer "F.Fab")
		)
		(fp_line
			(start -0.494 -0.25)
			(end 0.504 -0.25)
			(stroke
				(width 0.15)
				(type solid)
			)
			(layer "F.Fab")
		)
		(fp_text user "${REFERENCE}"
			(at -0.939 4.599 180)
			(layer "F.Fab")
			(effects
				(font
					(size 0.7 0.7)
					(thickness 0.15)
				)
				(justify left bottom)
			)
		)
		(fp_text user "License: Apache-2.0"
			(at -0.939 5.799 180)
			(layer "F.Fab")
			(effects
				(font
					(size 0.7 0.7)
					(thickness 0.15)
				)
				(justify left bottom)
			)
		)
		(fp_text user "Author: Antmicro"
			(at -0.939 3.399 180)
			(layer "F.Fab")
			(effects
				(font
					(size 0.7 0.7)
					(thickness 0.15)
				)
				(justify left bottom)
			)
		)
		(pad "1" smd roundrect
			(at -0.48 0 180)
			(size 0.59 0.64)
			(layers "F.Cu" "F.Mask" "F.Paste")
			(roundrect_rratio 0.25)
			(net 23 "GND")
			(pintype "passive")
		)
		(pad "2" smd roundrect
			(at 0.48 0 180)
			(size 0.59 0.64)
			(layers "F.Cu" "F.Mask" "F.Paste")
			(roundrect_rratio 0.25)
			(net 18 "+1V88")
			(pintype "passive")
		)
	)
	(footprint "antmicro-footprints:C_0805_2012Metric"
		(layer "F.Cu")
		(at 119.65 111.75 180)
		(descr "Capacitor SMD 0805")
		(tags "capacitor SMD 0805")
		(property "Reference" "C9"
			(at -6.55 -4.45 180)
			(layer "F.SilkS")
			(effects
				(font
					(size 0.7 0.7)
					(thickness 0.15)
				)
			)
		)
		(property "Value" "C_22u_25V_0805"
			(at -2.055717 1.963152 180)
			(layer "F.Fab")
			(effects
				(font
					(size 0.7 0.7)
					(thickness 0.15)
				)
				(justify left bottom)
			)
		)
		(property "Datasheet" "https://product.samsungsem.com/mlcc/CL21A226MAYNNN.do"
			(at 0 0 180)
			(layer "F.Fab")
			(hide yes)
			(effects
				(font
					(size 1.27 1.27)
					(thickness 0.15)
				)
			)
		)
		(property "Description" "SMT Multilayer Ceramic Capacitor, 22uF, +/-20%, 25V, X5R, 0805 [2012 Metric]"
			(at 0 0 180)
			(layer "F.Fab")
			(hide yes)
			(effects
				(font
					(size 1.27 1.27)
					(thickness 0.15)
				)
			)
		)
		(property "MPN" "CL21A226MAYNNNE"
			(at 0 0 180)
			(unlocked yes)
			(layer "F.Fab")
			(hide yes)
			(effects
				(font
					(size 1 1)
					(thickness 0.15)
				)
			)
		)
		(property "Manufacturer" "Samsung Electro-Mechanics"
			(at 0 0 180)
			(unlocked yes)
			(layer "F.Fab")
			(hide yes)
			(effects
				(font
					(size 1 1)
					(thickness 0.15)
				)
			)
		)
		(property "License" "Apache-2.0"
			(at 0 0 180)
			(unlocked yes)
			(layer "F.Fab")
			(hide yes)
			(effects
				(font
					(size 1 1)
					(thickness 0.15)
				)
			)
		)
		(property "Author" "Antmicro"
			(at 0 0 180)
			(unlocked yes)
			(layer "F.Fab")
			(hide yes)
			(effects
				(font
					(size 1 1)
					(thickness 0.15)
				)
			)
		)
		(property "Val" "22u"
			(at 0 0 180)
			(unlocked yes)
			(layer "F.Fab")
			(hide yes)
			(effects
				(font
					(size 1 1)
					(thickness 0.15)
				)
			)
		)
		(property "Voltage" "25V"
			(at 0 0 180)
			(unlocked yes)
			(layer "F.Fab")
			(hide yes)
			(effects
				(font
					(size 1 1)
					(thickness 0.15)
				)
			)
		)
		(property "Dielectric" "X5R"
			(at 0 0 180)
			(unlocked yes)
			(layer "F.Fab")
			(hide yes)
			(effects
				(font
					(size 1 1)
					(thickness 0.15)
				)
			)
		)
		(property "Public" "False"
			(at 0 0 180)
			(unlocked yes)
			(layer "F.Fab")
			(hide yes)
			(effects
				(font
					(size 1 1)
					(thickness 0.15)
				)
			)
		)
		(sheetname "/PD and TB DC-DC/")
		(sheetfile "PD_and_TB_DC_DC.kicad_sch")
		(attr smd)
		(fp_line
			(start -0.3 0.7)
			(end 0.3 0.7)
			(stroke
				(width 0.15)
				(type solid)
			)
			(layer "F.SilkS")
		)
		(fp_line
			(start -0.3 -0.7)
			(end 0.3 -0.7)
			(stroke
				(width 0.15)
				(type solid)
			)
			(layer "F.SilkS")
		)
		(fp_rect
			(start 1.95 -0.9)
			(end -1.95 0.9)
			(stroke
				(width 0.05)
				(type default)
			)
			(fill no)
			(layer "F.CrtYd")
		)
		(fp_rect
			(start -0.95 -0.675)
			(end 0.95 0.675)
			(stroke
				(width 0.15)
				(type solid)
			)
			(fill no)
			(layer "F.Fab")
		)
		(fp_text user "${REFERENCE}"
			(at -1.9 3.947 180)
			(layer "F.Fab")
			(effects
				(font
					(size 0.7 0.7)
					(thickness 0.15)
				)
				(justify left bottom)
			)
		)
		(fp_text user "License: Apache-2.0"
			(at -1.9 4.947 180)
			(layer "F.Fab")
			(effects
				(font
					(size 0.7 0.7)
					(thickness 0.15)
				)
				(justify left bottom)
			)
		)
		(fp_text user "Author: Antmicro"
			(at -1.9 5.947 180)
			(layer "F.Fab")
			(effects
				(font
					(size 0.7 0.7)
					(thickness 0.15)
				)
				(justify left bottom)
			)
		)
		(pad "1" smd roundrect
			(at -1.1 0 180)
			(size 1.2 1.3)
			(layers "F.Cu" "F.Mask" "F.Paste")
			(roundrect_rratio 0.25)
			(net 23 "GND")
			(pintype "passive")
		)
		(pad "2" smd roundrect
			(at 1.1 0 180)
			(size 1.2 1.3)
			(layers "F.Cu" "F.Mask" "F.Paste")
			(roundrect_rratio 0.25)
			(net 161 "Net-(U2-VIN)")
			(pintype "passive")
		)
	)
	(footprint "antmicro-footprints:TSOT23-6"
		(layer "F.Cu")
		(at 117.55 142.825 -90)
		(property "Reference" "U1"
			(at -0.225 -2.85 270)
			(layer "F.SilkS")
			(effects
				(font
					(size 0.7 0.7)
					(thickness 0.15)
				)
				(justify left bottom)
			)
		)
		(property "Value" "AP22615A_TSOT26"
			(at 0 2.6 270)
			(layer "F.Fab")
			(effects
				(font
					(size 0.7 0.7)
					(thickness 0.15)
				)
				(justify left bottom)
			)
		)
		(property "Datasheet" "https://www.mouser.com/datasheet/2/115/DIOD_S_A0008958405_1-2543193.pdf"
			(at 0 0 270)
			(layer "F.Fab")
			(hide yes)
			(effects
				(font
					(size 1.27 1.27)
					(thickness 0.15)
				)
			)
		)
		(property "Description" "Power Load Distribution Switch, High Side, Active High, 1 Output, 5.5 V, 3.6 A, 0.04 ohm, TSOT-26-6"
			(at 0 0 270)
			(layer "F.Fab")
			(hide yes)
			(effects
				(font
					(size 1.27 1.27)
					(thickness 0.15)
				)
			)
		)
		(property "MPN" "AP22615AWU-7"
			(at 0 0 270)
			(unlocked yes)
			(layer "F.Fab")
			(hide yes)
			(effects
				(font
					(size 1 1)
					(thickness 0.15)
				)
			)
		)
		(property "Manufacturer" "Diodes Incorporated"
			(at 0 0 270)
			(unlocked yes)
			(layer "F.Fab")
			(hide yes)
			(effects
				(font
					(size 1 1)
					(thickness 0.15)
				)
			)
		)
		(property "Author" "Antmicro"
			(at 0 0 270)
			(unlocked yes)
			(layer "F.Fab")
			(hide yes)
			(effects
				(font
					(size 1 1)
					(thickness 0.15)
				)
			)
		)
		(property "License" "Apache-2.0"
			(at 0 0 270)
			(unlocked yes)
			(layer "F.Fab")
			(hide yes)
			(effects
				(font
					(size 1 1)
					(thickness 0.15)
				)
			)
		)
		(sheetname "/USB-C connector/")
		(sheetfile "USB-C_connector.kicad_sch")
		(attr smd)
		(fp_line
			(start -1 1.55)
			(end -1 1.4)
			(stroke
				(width 0.15)
				(type solid)
			)
			(layer "F.SilkS")
		)
		(fp_line
			(start 1 1.55)
			(end -1 1.55)
			(stroke
				(width 0.15)
				(type solid)
			)
			(layer "F.SilkS")
		)
		(fp_line
			(start 1 1.55)
			(end 1 1.4)
			(stroke
				(width 0.15)
				(type solid)
			)
			(layer "F.SilkS")
		)
		(fp_line
			(start 1 -1.497)
			(end 1 -1.375)
			(stroke
				(width 0.15)
				(type solid)
			)
			(layer "F.SilkS")
		)
		(fp_line
			(start 1 -1.497)
			(end -1 -1.5)
			(stroke
				(width 0.15)
				(type solid)
			)
			(layer "F.SilkS")
		)
		(fp_line
			(start -1 -1.5)
			(end -1 -1.375)
			(stroke
				(width 0.15)
				(type solid)
			)
			(layer "F.SilkS")
		)
		(fp_circle
			(center -1.44 -1.5)
			(end -1.39 -1.5)
			(stroke
				(width 0.15)
				(type solid)
			)
			(fill yes)
			(layer "F.SilkS")
		)
		(fp_rect
			(start 1.93 -1.7)
			(end -1.93 1.7)
			(stroke
				(width 0.05)
				(type solid)
			)
			(fill no)
			(layer "F.CrtYd")
		)
		(fp_line
			(start -0.45 -1.521)
			(end -0.876 -1.096)
			(stroke
				(width 0.15)
				(type solid)
			)
			(layer "F.Fab")
		)
		(fp_rect
			(start 0.875 1.528)
			(end -0.875 -1.525)
			(stroke
				(width 0.15)
				(type solid)
			)
			(fill no)
			(layer "F.Fab")
		)
		(fp_text user "${REFERENCE}"
			(at -1.93 3.8 270)
			(layer "F.Fab")
			(effects
				(font
					(size 0.7 0.7)
					(thickness 0.15)
				)
				(justify left bottom)
			)
		)
		(fp_text user "Author: Antmicro"
			(at -1.93 5 270)
			(layer "F.Fab")
			(effects
				(font
					(size 0.7 0.7)
					(thickness 0.15)
				)
				(justify left bottom)
			)
		)
		(fp_text user "License: Apache-2.0"
			(at -1.93 6.199 270)
			(layer "F.Fab")
			(effects
				(font
					(size 0.7 0.7)
					(thickness 0.15)
				)
				(justify left bottom)
			)
		)
		(pad "1" smd rect
			(at -1.301 -0.947 180)
			(size 0.7 1.2)
			(layers "F.Cu" "F.Mask" "F.Paste")
			(net 53 "+5V_USB")
			(pinfunction "OUT")
			(pintype "power_out")
		)
		(pad "2" smd rect
			(at -1.301 0.004 180)
			(size 0.7 1.2)
			(layers "F.Cu" "F.Mask" "F.Paste")
			(net 23 "GND")
			(pinfunction "GND")
			(pintype "power_in")
		)
		(pad "3" smd rect
			(at -1.301 0.954 180)
			(size 0.7 1.2)
			(layers "F.Cu" "F.Mask" "F.Paste")
			(net 447 "unconnected-(U1-FLG-Pad3)")
			(pinfunction "FLG")
			(pintype "output+no_connect")
		)
		(pad "4" smd rect
			(at 1.299 0.954 180)
			(size 0.7 1.2)
			(layers "F.Cu" "F.Mask" "F.Paste")
			(net 215 "/USB-C connector/VBUS")
			(pinfunction "EN")
			(pintype "input")
		)
		(pad "5" smd rect
			(at 1.299 0.004 180)
			(size 0.7 1.2)
			(layers "F.Cu" "F.Mask" "F.Paste")
			(net 434 "Net-(U1-ISET)")
			(pinfunction "ISET")
			(pintype "passive")
		)
		(pad "6" smd rect
			(at 1.299 -0.947 180)
			(size 0.7 1.2)
			(layers "F.Cu" "F.Mask" "F.Paste")
			(net 215 "/USB-C connector/VBUS")
			(pinfunction "IN")
			(pintype "power_in")
		)
	)
	(footprint "antmicro-footprints:R_0402_1005Metric"
		(layer "F.Cu")
		(at 155.255 65.174999 90)
		(descr "Resistor SMD 0402")
		(tags "resistor SMD 0402")
		(property "Reference" "R157"
			(at 2.374999 0.095001 90)
			(layer "F.SilkS")
			(effects
				(font
					(size 0.7 0.7)
					(thickness 0.15)
				)
			)
		)
		(property "Value" "R_100k_0402"
			(at -1.011843 1.772047 90)
			(layer "F.Fab")
			(effects
				(font
					(size 0.7 0.7)
					(thickness 0.15)
				)
				(justify left bottom)
			)
		)
		(property "Datasheet" "https://www.bourns.com/docs/product-datasheets/cr.pdf"
			(at 0 0 90)
			(layer "F.Fab")
			(hide yes)
			(effects
				(font
					(size 1.27 1.27)
					(thickness 0.15)
				)
			)
		)
		(property "Description" "SMD Chip Resistor, 100 kohm, ± 1%, 62.5 mW, 0402 [1005 Metric], Thick Film, General Purpose"
			(at 0 0 90)
			(layer "F.Fab")
			(hide yes)
			(effects
				(font
					(size 1.27 1.27)
					(thickness 0.15)
				)
			)
		)
		(property "MPN" "CR0402-FX-1003GLF"
			(at 0 0 90)
			(unlocked yes)
			(layer "F.Fab")
			(hide yes)
			(effects
				(font
					(size 1 1)
					(thickness 0.15)
				)
			)
		)
		(property "Manufacturer" "Bourns"
			(at 0 0 90)
			(unlocked yes)
			(layer "F.Fab")
			(hide yes)
			(effects
				(font
					(size 1 1)
					(thickness 0.15)
				)
			)
		)
		(property "License" "Apache-2.0"
			(at 0 0 90)
			(unlocked yes)
			(layer "F.Fab")
			(hide yes)
			(effects
				(font
					(size 1 1)
					(thickness 0.15)
				)
			)
		)
		(property "Author" "Antmicro"
			(at 0 0 90)
			(unlocked yes)
			(layer "F.Fab")
			(hide yes)
			(effects
				(font
					(size 1 1)
					(thickness 0.15)
				)
			)
		)
		(property "Val" "100k"
			(at 0 0 90)
			(unlocked yes)
			(layer "F.Fab")
			(hide yes)
			(effects
				(font
					(size 1 1)
					(thickness 0.15)
				)
			)
		)
		(property "Tolerance" "1%"
			(at 0 0 90)
			(unlocked yes)
			(layer "F.Fab")
			(hide yes)
			(effects
				(font
					(size 1 1)
					(thickness 0.15)
				)
			)
		)
		(sheetname "/X710-AT2 Misc/")
		(sheetfile "x710-at2-mics.kicad_sch")
		(attr smd)
		(fp_rect
			(start -0.925 -0.47)
			(end 0.925 0.47)
			(stroke
				(width 0.05)
				(type default)
			)
			(fill no)
			(layer "F.CrtYd")
		)
		(fp_rect
			(start -0.5 -0.25)
			(end 0.5 0.25)
			(stroke
				(width 0.15)
				(type solid)
			)
			(fill no)
			(layer "F.Fab")
		)
		(fp_text user "License: Apache-2.0"
			(at -0.95 5.169 90)
			(layer "F.Fab")
			(effects
				(font
					(size 0.7 0.7)
					(thickness 0.15)
				)
				(justify left bottom)
			)
		)
		(fp_text user "${REFERENCE}"
			(at -0.95 3.168 90)
			(layer "F.Fab")
			(effects
				(font
					(size 0.7 0.7)
					(thickness 0.15)
				)
				(justify left bottom)
			)
		)
		(fp_text user "Author: Antmicro"
			(at -0.95 4.169 90)
			(layer "F.Fab")
			(effects
				(font
					(size 0.7 0.7)
					(thickness 0.15)
				)
				(justify left bottom)
			)
		)
		(pad "1" smd roundrect
			(at -0.48 0 90)
			(size 0.59 0.64)
			(layers "F.Cu" "F.Mask" "F.Paste")
			(roundrect_rratio 0.25)
			(net 23 "GND")
			(pintype "passive")
		)
		(pad "2" smd roundrect
			(at 0.48 0 90)
			(size 0.59 0.64)
			(layers "F.Cu" "F.Mask" "F.Paste")
			(roundrect_rratio 0.25)
			(net 144 "/X710-AT2 Misc/NCSI.REF_CLK")
			(pintype "passive")
		)
	)
)
